# S9S_MB_2U (Grand Teton) — schematic parts with pin connectivity, parts 723–861 of 6093; source: Cadence DE-HDL packaged netlist (pstxprt.dat, pstxnet.dat, pstchip.dat)

C908  Q_CAP_DIFFBUS  DIFF BUS_0.22UF 6.3V 20% X6S  pkg C0201  page 173 : 1 = P5E_CPU0_PE0_TX_C_DN<12> ; 2 = P5E_CPU0_PE0_TX_DN<12>
C909  Q_CAP_DIFFBUS  DIFF BUS_0.22UF 6.3V 20% X6S  pkg C0201  page 173 : 1 = P5E_CPU0_PE0_TX_C_DP<12> ; 2 = P5E_CPU0_PE0_TX_DP<12>
C910  Q_CAP_DIFFBUS  DIFF BUS_0.22UF 6.3V 20% X6S  pkg C0201  page 173 : 1 = P5E_CPU0_PE0_TX_C_DN<11> ; 2 = P5E_CPU0_PE0_TX_DN<11>
C911  Q_CAP_DIFFBUS  DIFF BUS_0.22UF 6.3V 20% X6S  pkg C0201  page 173 : 1 = P5E_CPU0_PE0_TX_C_DP<11> ; 2 = P5E_CPU0_PE0_TX_DP<11>
C912  Q_CAP_DIFFBUS  DIFF BUS_0.22UF 6.3V 20% X6S  pkg C0201  page 173 : 1 = P5E_CPU0_PE0_TX_C_DN<10> ; 2 = P5E_CPU0_PE0_TX_DN<10>
C913  Q_CAP_DIFFBUS  DIFF BUS_0.22UF 6.3V 20% X6S  pkg C0201  page 173 : 1 = P5E_CPU0_PE0_TX_C_DP<10> ; 2 = P5E_CPU0_PE0_TX_DP<10>
C914  Q_CAP_DIFFBUS  DIFF BUS_0.22UF 6.3V 20% X6S  pkg C0201  page 173 : 1 = P5E_CPU0_PE0_TX_C_DN<9> ; 2 = P5E_CPU0_PE0_TX_DN<9>
C915  Q_CAP_DIFFBUS  DIFF BUS_0.22UF 6.3V 20% X6S  pkg C0201  page 173 : 1 = P5E_CPU0_PE0_TX_C_DP<9> ; 2 = P5E_CPU0_PE0_TX_DP<9>
C916  Q_CAP_DIFFBUS  DIFF BUS_0.22UF 6.3V 20% X6S  pkg C0201  page 173 : 1 = P5E_CPU0_PE0_TX_C_DN<8> ; 2 = P5E_CPU0_PE0_TX_DN<8>
C917  Q_CAP_DIFFBUS  DIFF BUS_0.22UF 6.3V 20% X6S  pkg C0201  page 173 : 1 = P5E_CPU0_PE0_TX_C_DP<8> ; 2 = P5E_CPU0_PE0_TX_DP<8>
C918  Q_CAP_DIFFBUS  DIFF BUS_0.22UF 6.3V 20% X6S  pkg C0201  page 173 : 1 = P5E_CPU0_PE0_TX_C_DN<7> ; 2 = P5E_CPU0_PE0_TX_DN<7>
C919  Q_CAP_DIFFBUS  DIFF BUS_0.22UF 6.3V 20% X6S  pkg C0201  page 173 : 1 = P5E_CPU0_PE0_TX_C_DP<7> ; 2 = P5E_CPU0_PE0_TX_DP<7>
C920  Q_CAP_DIFFBUS  DIFF BUS_0.22UF 6.3V 20% X6S  pkg C0201  page 173 : 1 = P5E_CPU0_PE0_TX_C_DN<6> ; 2 = P5E_CPU0_PE0_TX_DN<6>
C921  Q_CAP_DIFFBUS  DIFF BUS_0.22UF 6.3V 20% X6S  pkg C0201  page 173 : 1 = P5E_CPU0_PE0_TX_C_DP<6> ; 2 = P5E_CPU0_PE0_TX_DP<6>
C922  Q_CAP_DIFFBUS  DIFF BUS_0.22UF 6.3V 20% X6S  pkg C0201  page 173 : 1 = P5E_CPU0_PE0_TX_C_DN<5> ; 2 = P5E_CPU0_PE0_TX_DN<5>
C923  Q_CAP_DIFFBUS  DIFF BUS_0.22UF 6.3V 20% X6S  pkg C0201  page 173 : 1 = P5E_CPU0_PE0_TX_C_DP<5> ; 2 = P5E_CPU0_PE0_TX_DP<5>
C924  Q_CAP_DIFFBUS  DIFF BUS_0.22UF 6.3V 20% X6S  pkg C0201  page 173 : 1 = P5E_CPU0_PE0_TX_C_DN<4> ; 2 = P5E_CPU0_PE0_TX_DN<4>
C925  Q_CAP_DIFFBUS  DIFF BUS_0.22UF 6.3V 20% X6S  pkg C0201  page 173 : 1 = P5E_CPU0_PE0_TX_C_DP<4> ; 2 = P5E_CPU0_PE0_TX_DP<4>
C926  Q_CAP_DIFFBUS  DIFF BUS_0.22UF 6.3V 20% X6S  pkg C0201  page 173 : 1 = P5E_CPU0_PE0_TX_C_DN<3> ; 2 = P5E_CPU0_PE0_TX_DN<3>
C927  Q_CAP_DIFFBUS  DIFF BUS_0.22UF 6.3V 20% X6S  pkg C0201  page 173 : 1 = P5E_CPU0_PE0_TX_C_DP<3> ; 2 = P5E_CPU0_PE0_TX_DP<3>
C928  Q_CAP_DIFFBUS  DIFF BUS_0.22UF 6.3V 20% X6S  pkg C0201  page 173 : 1 = P5E_CPU0_PE0_TX_C_DN<2> ; 2 = P5E_CPU0_PE0_TX_DN<2>
C929  Q_CAP_DIFFBUS  DIFF BUS_0.22UF 6.3V 20% X6S  pkg C0201  page 173 : 1 = P5E_CPU0_PE0_TX_C_DP<2> ; 2 = P5E_CPU0_PE0_TX_DP<2>
C930  Q_CAP_DIFFBUS  DIFF BUS_0.22UF 6.3V 20% X6S  pkg C0201  page 173 : 1 = P5E_CPU0_PE0_TX_C_DN<1> ; 2 = P5E_CPU0_PE0_TX_DN<1>
C931  Q_CAP_DIFFBUS  DIFF BUS_0.22UF 6.3V 20% X6S  pkg C0201  page 173 : 1 = P5E_CPU0_PE0_TX_C_DP<1> ; 2 = P5E_CPU0_PE0_TX_DP<1>
C932  Q_CAP_DIFFBUS  DIFF BUS_0.22UF 6.3V 20% X6S  pkg C0201  page 173 : 1 = P5E_CPU0_PE0_TX_C_DN<0> ; 2 = P5E_CPU0_PE0_TX_DN<0>
C933  Q_CAP_DIFFBUS  DIFF BUS_0.22UF 6.3V 20% X6S  pkg C0201  page 173 : 1 = P5E_CPU0_PE0_TX_C_DP<0> ; 2 = P5E_CPU0_PE0_TX_DP<0>
C934  Q_CAP_DIFFBUS  DIFF BUS_0.22UF 6.3V 20% X6S  pkg C0201  page 173 : 1 = P5E_CPU0_PE2_TX_C_DN<15> ; 2 = P5E_CPU0_PE2_TX_DN<15>
C935  Q_CAP_DIFFBUS  DIFF BUS_0.22UF 6.3V 20% X6S  pkg C0201  page 173 : 1 = P5E_CPU0_PE2_TX_C_DP<15> ; 2 = P5E_CPU0_PE2_TX_DP<15>
C936  Q_CAP_DIFFBUS  DIFF BUS_0.22UF 6.3V 20% X6S  pkg C0201  page 173 : 1 = P5E_CPU0_PE2_TX_C_DN<14> ; 2 = P5E_CPU0_PE2_TX_DN<14>
C937  Q_CAP_DIFFBUS  DIFF BUS_0.22UF 6.3V 20% X6S  pkg C0201  page 173 : 1 = P5E_CPU0_PE2_TX_C_DP<14> ; 2 = P5E_CPU0_PE2_TX_DP<14>
C938  Q_CAP_DIFFBUS  DIFF BUS_0.22UF 6.3V 20% X6S  pkg C0201  page 173 : 1 = P5E_CPU0_PE2_TX_C_DN<13> ; 2 = P5E_CPU0_PE2_TX_DN<13>
C939  Q_CAP_DIFFBUS  DIFF BUS_0.22UF 6.3V 20% X6S  pkg C0201  page 173 : 1 = P5E_CPU0_PE2_TX_C_DP<13> ; 2 = P5E_CPU0_PE2_TX_DP<13>
C940  Q_CAP_DIFFBUS  DIFF BUS_0.22UF 6.3V 20% X6S  pkg C0201  page 173 : 1 = P5E_CPU0_PE2_TX_C_DN<12> ; 2 = P5E_CPU0_PE2_TX_DN<12>
C941  Q_CAP_DIFFBUS  DIFF BUS_0.22UF 6.3V 20% X6S  pkg C0201  page 173 : 1 = P5E_CPU0_PE2_TX_C_DP<12> ; 2 = P5E_CPU0_PE2_TX_DP<12>
C942  Q_CAP_DIFFBUS  DIFF BUS_0.22UF 6.3V 20% X6S  pkg C0201  page 173 : 1 = P5E_CPU0_PE2_TX_C_DN<11> ; 2 = P5E_CPU0_PE2_TX_DN<11>
C943  Q_CAP_DIFFBUS  DIFF BUS_0.22UF 6.3V 20% X6S  pkg C0201  page 173 : 1 = P5E_CPU0_PE2_TX_C_DP<11> ; 2 = P5E_CPU0_PE2_TX_DP<11>
C944  Q_CAP_DIFFBUS  DIFF BUS_0.22UF 6.3V 20% X6S  pkg C0201  page 173 : 1 = P5E_CPU0_PE2_TX_C_DN<10> ; 2 = P5E_CPU0_PE2_TX_DN<10>
C945  Q_CAP_DIFFBUS  DIFF BUS_0.22UF 6.3V 20% X6S  pkg C0201  page 173 : 1 = P5E_CPU0_PE2_TX_C_DP<10> ; 2 = P5E_CPU0_PE2_TX_DP<10>
C946  Q_CAP_DIFFBUS  DIFF BUS_0.22UF 6.3V 20% X6S  pkg C0201  page 173 : 1 = P5E_CPU0_PE2_TX_C_DN<9> ; 2 = P5E_CPU0_PE2_TX_DN<9>
C947  Q_CAP_DIFFBUS  DIFF BUS_0.22UF 6.3V 20% X6S  pkg C0201  page 173 : 1 = P5E_CPU0_PE2_TX_C_DP<9> ; 2 = P5E_CPU0_PE2_TX_DP<9>
C948  Q_CAP_DIFFBUS  DIFF BUS_0.22UF 6.3V 20% X6S  pkg C0201  page 173 : 1 = P5E_CPU0_PE2_TX_C_DN<8> ; 2 = P5E_CPU0_PE2_TX_DN<8>
C949  Q_CAP_DIFFBUS  DIFF BUS_0.22UF 6.3V 20% X6S  pkg C0201  page 173 : 1 = P5E_CPU0_PE2_TX_C_DP<8> ; 2 = P5E_CPU0_PE2_TX_DP<8>
C950  Q_CAP_DIFFBUS  DIFF BUS_0.22UF 6.3V 20% X6S  pkg C0201  page 173 : 1 = P5E_CPU0_PE2_TX_C_DN<7> ; 2 = P5E_CPU0_PE2_TX_DN<7>
C951  Q_CAP_DIFFBUS  DIFF BUS_0.22UF 6.3V 20% X6S  pkg C0201  page 173 : 1 = P5E_CPU0_PE2_TX_C_DP<7> ; 2 = P5E_CPU0_PE2_TX_DP<7>
C952  Q_CAP_DIFFBUS  DIFF BUS_0.22UF 6.3V 20% X6S  pkg C0201  page 173 : 1 = P5E_CPU0_PE2_TX_C_DN<6> ; 2 = P5E_CPU0_PE2_TX_DN<6>
C953  Q_CAP_DIFFBUS  DIFF BUS_0.22UF 6.3V 20% X6S  pkg C0201  page 173 : 1 = P5E_CPU0_PE2_TX_C_DP<6> ; 2 = P5E_CPU0_PE2_TX_DP<6>
C954  Q_CAP_DIFFBUS  DIFF BUS_0.22UF 6.3V 20% X6S  pkg C0201  page 173 : 1 = P5E_CPU0_PE2_TX_C_DN<5> ; 2 = P5E_CPU0_PE2_TX_DN<5>
C955  Q_CAP_DIFFBUS  DIFF BUS_0.22UF 6.3V 20% X6S  pkg C0201  page 173 : 1 = P5E_CPU0_PE2_TX_C_DP<5> ; 2 = P5E_CPU0_PE2_TX_DP<5>
C956  Q_CAP_DIFFBUS  DIFF BUS_0.22UF 6.3V 20% X6S  pkg C0201  page 173 : 1 = P5E_CPU0_PE2_TX_C_DN<4> ; 2 = P5E_CPU0_PE2_TX_DN<4>
C957  Q_CAP_DIFFBUS  DIFF BUS_0.22UF 6.3V 20% X6S  pkg C0201  page 173 : 1 = P5E_CPU0_PE2_TX_C_DP<4> ; 2 = P5E_CPU0_PE2_TX_DP<4>
C958  Q_CAP_DIFFBUS  DIFF BUS_0.22UF 6.3V 20% X6S  pkg C0201  page 173 : 1 = P5E_CPU0_PE2_TX_C_DN<3> ; 2 = P5E_CPU0_PE2_TX_DN<3>
C959  Q_CAP_DIFFBUS  DIFF BUS_0.22UF 6.3V 20% X6S  pkg C0201  page 173 : 1 = P5E_CPU0_PE2_TX_C_DP<3> ; 2 = P5E_CPU0_PE2_TX_DP<3>
C960  Q_CAP_DIFFBUS  DIFF BUS_0.22UF 6.3V 20% X6S  pkg C0201  page 173 : 1 = P5E_CPU0_PE2_TX_C_DN<2> ; 2 = P5E_CPU0_PE2_TX_DN<2>
C961  Q_CAP_DIFFBUS  DIFF BUS_0.22UF 6.3V 20% X6S  pkg C0201  page 173 : 1 = P5E_CPU0_PE2_TX_C_DP<2> ; 2 = P5E_CPU0_PE2_TX_DP<2>
C962  Q_CAP_DIFFBUS  DIFF BUS_0.22UF 6.3V 20% X6S  pkg C0201  page 173 : 1 = P5E_CPU0_PE2_TX_C_DN<1> ; 2 = P5E_CPU0_PE2_TX_DN<1>
C963  Q_CAP_DIFFBUS  DIFF BUS_0.22UF 6.3V 20% X6S  pkg C0201  page 173 : 1 = P5E_CPU0_PE2_TX_C_DP<1> ; 2 = P5E_CPU0_PE2_TX_DP<1>
C964  Q_CAP_DIFFBUS  DIFF BUS_0.22UF 6.3V 20% X6S  pkg C0201  page 173 : 1 = P5E_CPU0_PE2_TX_C_DN<0> ; 2 = P5E_CPU0_PE2_TX_DN<0>
C965  Q_CAP_DIFFBUS  DIFF BUS_0.22UF 6.3V 20% X6S  pkg C0201  page 173 : 1 = P5E_CPU0_PE2_TX_C_DP<0> ; 2 = P5E_CPU0_PE2_TX_DP<0>
C966  Q_CAP  10UF 6.3V 20% X6S  pkg C0402  page 74 : 1 = PVCCIN_CPU0 ; 2 = GND
C967  Q_CAP  10UF 6.3V 20% X6S  pkg C0402  page 74 : 1 = PVCCIN_CPU0 ; 2 = GND
C968  Q_CAP  10UF 6.3V 20% X6S  pkg C0402  page 74 : 1 = PVCCIN_CPU0 ; 2 = GND
C969  Q_CAP  10UF 6.3V 20% X6S  pkg C0402  page 74 : 1 = PVCCIN_CPU0 ; 2 = GND
C970  Q_CAP  10UF 6.3V 20% X6S  pkg C0402  page 74 : 1 = PVCCIN_CPU0 ; 2 = GND
C971  Q_CAP  10UF 6.3V 20% X6S  pkg C0402  page 74 : 1 = PVCCIN_CPU0 ; 2 = GND
C972  Q_CAP  10UF 6.3V 20% X6S  pkg C0402  page 74 : 1 = PVCCIN_CPU0 ; 2 = GND
C973  Q_CAP  10UF 6.3V 20% X6S  pkg C0402  page 74 : 1 = PVCCIN_CPU0 ; 2 = GND
C974  Q_CAP  10UF 6.3V 20% X6S  pkg C0402  page 74 : 1 = PVCCIN_CPU0 ; 2 = GND
C975  Q_CAP  10UF 6.3V 20% X6S  pkg C0402  page 74 : 1 = PVCCIN_CPU0 ; 2 = GND
C976  Q_CAP  10UF 6.3V 20% X6S  pkg C0402  page 74 : 1 = PVCCIN_CPU0 ; 2 = GND
C977  Q_CAP  10UF 6.3V 20% X6S  pkg C0402  page 74 : 1 = PVCCIN_CPU0 ; 2 = GND
C978  Q_CAP  10UF 6.3V 20% X6S  pkg C0402  page 74 : 1 = PVCCIN_CPU0 ; 2 = GND
C979  Q_CAP  10UF 6.3V 20% X6S  pkg C0402  page 74 : 1 = PVCCIN_CPU0 ; 2 = GND
C980  Q_CAP  10UF 6.3V 20% X6S  pkg C0402  page 74 : 1 = PVCCIN_CPU0 ; 2 = GND
C981  Q_CAP  10UF 6.3V 20% X6S  pkg C0402  page 74 : 1 = PVCCIN_CPU0 ; 2 = GND
C982  Q_CAP  10UF 6.3V 20% X6S  pkg C0402  page 74 : 1 = PVCCIN_CPU0 ; 2 = GND
C983  Q_CAP  10UF 6.3V 20% X6S  pkg C0402  page 74 : 1 = PVCCIN_CPU0 ; 2 = GND
C984  Q_CAP  10UF 6.3V 20% X6S  pkg C0402  page 74 : 1 = PVCCIN_CPU0 ; 2 = GND
C985  Q_CAP  10UF 6.3V 20% X6S  pkg C0402  page 74 : 1 = PVCCIN_CPU0 ; 2 = GND
C986  Q_CAP  10UF 6.3V 20% X6S  pkg C0402  page 74 : 1 = PVCCIN_CPU0 ; 2 = GND
C987  Q_CAP  10UF 6.3V 20% X6S  pkg C0402  page 74 : 1 = PVCCIN_CPU0 ; 2 = GND
C988  Q_CAP  10UF 6.3V 20% X6S  pkg C0402  page 74 : 1 = PVCCIN_CPU0 ; 2 = GND
C989  Q_CAP  10UF 6.3V 20% X6S  pkg C0402  page 74 : 1 = PVCCIN_CPU0 ; 2 = GND
C990  Q_CAP  10UF 6.3V 20% X6S  pkg C0402  page 74 : 1 = PVCCIN_CPU0 ; 2 = GND
C991  Q_CAP  10UF 6.3V 20% X6S  pkg C0402  page 74 : 1 = PVCCIN_CPU0 ; 2 = GND
C992  Q_CAP  10UF 6.3V 20% X6S  pkg C0402  page 74 : 1 = PVCCIN_CPU0 ; 2 = GND
C993  Q_CAP  10UF 6.3V 20% X6S  pkg C0402  page 74 : 1 = PVCCIN_CPU0 ; 2 = GND
C994  Q_CAP  10UF 6.3V 20% X6S  pkg C0402  page 74 : 1 = PVCCIN_CPU0 ; 2 = GND
C995  Q_CAP  10UF 6.3V 20% X6S  pkg C0402  page 74 : 1 = PVCCIN_CPU0 ; 2 = GND
C996  Q_CAP  10UF 6.3V 20% X6S  pkg C0402  page 74 : 1 = PVCCIN_CPU0 ; 2 = GND
C997  Q_CAP  10UF 6.3V 20% X6S  pkg C0402  page 74 : 1 = PVCCIN_CPU0 ; 2 = GND
C998  Q_CAP  10UF 6.3V 20% X6S  pkg C0402  page 74 : 1 = PVCCIN_CPU0 ; 2 = GND
C999  Q_CAP  10UF 6.3V 20% X6S  pkg C0402  page 74 : 1 = PVCCIN_CPU0 ; 2 = GND
C1000  Q_CAP  10UF 6.3V 20% X6S  pkg C0402  page 74 : 1 = PVCCIN_CPU0 ; 2 = GND
C1001  Q_CAP  10UF 6.3V 20% X6S  pkg C0402  page 74 : 1 = PVCCIN_CPU0 ; 2 = GND
C1002  Q_CAP  10UF 6.3V 20% X6S  pkg C0402  page 74 : 1 = PVCCIN_CPU0 ; 2 = GND
C1003  Q_CAP  10UF 6.3V 20% X6S  pkg C0402  page 74 : 1 = PVCCIN_CPU0 ; 2 = GND
C1004  Q_CAP  10UF 6.3V 20% X6S  pkg C0402  page 74 : 1 = PVCCIN_CPU0 ; 2 = GND
C1005  Q_CAP  10UF 6.3V 20% X6S  pkg C0402  page 74 : 1 = PVCCIN_CPU0 ; 2 = GND
C1006  Q_CAP  22UF 4V 20% X6S  pkg C0402  page 74 : 1 = PVCCIN_CPU0 ; 2 = GND
C1007  Q_CAP  22UF 4V 20% X6S  pkg C0402  page 74 : 1 = PVCCIN_CPU0 ; 2 = GND
C1008  Q_CAP  22UF 4V 20% X6S  pkg C0402  page 74 : 1 = PVCCIN_CPU0 ; 2 = GND
C1009  Q_CAP  22UF 4V 20% X6S  pkg C0402  page 74 : 1 = PVCCIN_CPU0 ; 2 = GND
C1010  Q_CAP  22UF 4V 20% X6S  pkg C0402  page 74 : 1 = PVCCIN_CPU0 ; 2 = GND
C1011  Q_CAP  22UF 4V 20% X6S  pkg C0402  page 74 : 1 = PVCCIN_CPU0 ; 2 = GND
C1012  Q_CAP  22UF 4V 20% X6S  pkg C0402  page 74 : 1 = PVCCIN_CPU0 ; 2 = GND
C1013  Q_CAP  22UF 4V 20% X6S  pkg C0402  page 74 : 1 = PVCCIN_CPU0 ; 2 = GND
C1014  Q_CAP  22UF 4V 20% X6S  pkg C0402  page 74 : 1 = PVCCIN_CPU0 ; 2 = GND
C1015  Q_CAP  22UF 4V 20% X6S  pkg C0402  page 74 : 1 = PVCCIN_CPU0 ; 2 = GND
C1016  Q_CAP  22UF 4V 20% X6S  pkg C0402  page 74 : 1 = PVCCIN_CPU0 ; 2 = GND
C1017  Q_CAP  22UF 4V 20% X6S  pkg C0402  page 74 : 1 = PVCCIN_CPU0 ; 2 = GND
C1018  Q_CAP  22UF 4V 20% X6S  pkg C0402  page 74 : 1 = PVCCIN_CPU0 ; 2 = GND
C1019  Q_CAP  22UF 4V 20% X6S  pkg C0402  page 74 : 1 = PVCCIN_CPU0 ; 2 = GND
C1020  Q_CAP  22UF 4V 20% X6S  pkg C0402  page 74 : 1 = PVCCIN_CPU0 ; 2 = GND
C1021  Q_CAP  22UF 4V 20% X6S  pkg C0402  page 74 : 1 = PVCCIN_CPU0 ; 2 = GND
C1022  Q_CAP  22UF 4V 20% X6S  pkg C0402  page 74 : 1 = PVCCIN_CPU0 ; 2 = GND
C1023  Q_CAP  22UF 4V 20% X6S  pkg C0402  page 74 : 1 = PVCCIN_CPU0 ; 2 = GND
C1024  Q_CAP  22UF 4V 20% X6S  pkg C0402  page 74 : 1 = PVCCIN_CPU0 ; 2 = GND
C1025  Q_CAP  22UF 4V 20% X6S  pkg C0402  page 74 : 1 = PVCCIN_CPU0 ; 2 = GND
C1026  Q_CAP  22UF 4V 20% X6S  pkg C0402  page 74 : 1 = PVCCIN_CPU0 ; 2 = GND
C1027  Q_CAP  22UF 4V 20% X6S  pkg C0402  page 74 : 1 = PVCCIN_CPU0 ; 2 = GND
C1028  Q_CAP  22UF 4V 20% X6S  pkg C0402  page 74 : 1 = PVCCIN_CPU0 ; 2 = GND
C1029  Q_CAP  22UF 4V 20% X6S  pkg C0402  page 74 : 1 = PVCCIN_CPU0 ; 2 = GND
C1030  Q_CAP  22UF 4V 20% X6S  pkg C0402  page 74 : 1 = PVCCIN_CPU0 ; 2 = GND
C1031  Q_CAP  22UF 4V 20% X6S  pkg C0402  page 74 : 1 = PVCCIN_CPU0 ; 2 = GND
C1032  Q_CAP  22UF 4V 20% X6S  pkg C0402  page 74 : 1 = PVCCIN_CPU0 ; 2 = GND
C1033  Q_CAP  22UF 4V 20% X6S  pkg C0402  page 74 : 1 = PVCCIN_CPU0 ; 2 = GND
C1034  Q_CAP  22UF 4V 20% X6S  pkg C0402  page 74 : 1 = PVCCIN_CPU0 ; 2 = GND
C1035  Q_CAP  22UF 4V 20% X6S  pkg C0402  page 74 : 1 = PVCCIN_CPU0 ; 2 = GND
C1036  Q_CAP  22UF 4V 20% X6S  pkg C0402  page 74 : 1 = PVCCIN_CPU0 ; 2 = GND
C1037  Q_CAP  22UF 4V 20% X6S  pkg C0402  page 74 : 1 = PVCCIN_CPU0 ; 2 = GND
C1038  Q_CAP  22UF 4V 20% X6S  pkg C0402  page 74 : 1 = PVCCIN_CPU0 ; 2 = GND
C1039  Q_CAP  22UF 4V 20% X6S  pkg C0402  page 74 : 1 = PVCCIN_CPU0 ; 2 = GND
C1040  Q_CAP  22UF 4V 20% X6S  pkg C0402  page 74 : 1 = PVCCIN_CPU0 ; 2 = GND
C1041  Q_CAP  22UF 4V 20% X6S  pkg C0402  page 74 : 1 = PVCCIN_CPU0 ; 2 = GND
C1042  Q_CAP  100NF 50V 10% X7R  pkg C0402  page 260 : 1 = P5V_AUX ; 2 = GND
C1043  Q_CAP  22UF 4V 20% X6S  pkg C0402  page 74 : 1 = PVCCIN_CPU0 ; 2 = GND
C1044  Q_CAP  22UF 4V 20% X6S  pkg C0402  page 74 : 1 = PVCCIN_CPU0 ; 2 = GND
C1045  Q_CAP  22UF 4V 20% X6S  pkg C0402  page 74 : 1 = PVCCIN_CPU0 ; 2 = GND
C1096  Q_CAP  0.1UF 6.3V 10% X6S  pkg C0201  page 181 : 1 = USB3_PCH_TX_DP<4> ; 2 = USB3_PCH_TX_C_DP<4>
